(kicad_pcb
	(version 20260206)
	(generator "pcbnew")
	(generator_version "10.0")
	(general
		(thickness 1.6)
		(legacy_teardrops no)
	)
	(paper "A4")
	(title_block
		(title "01162023_DA0F0TEBIF0_F0T_Expander_BD_F_brd_V02_OCP.brd")
		(comment 1 "Grand Teton / footprints 5787-5792 of 9728")
	)
	(layers
		(0 "F.Cu" signal "TOP")
		(4 "In1.Cu" signal "GND")
		(6 "In2.Cu" signal "VCC")
		(8 "In3.Cu" signal "VCC1")
		(10 "In4.Cu" signal "GND1")
		(12 "In5.Cu" signal "IN1")
		(14 "In6.Cu" signal "GND2")
		(16 "In7.Cu" signal "IN2")
		(18 "In8.Cu" signal "GND3")
		(20 "In9.Cu" signal "IN3")
		(22 "In10.Cu" signal "GND4")
		(24 "In11.Cu" signal "IN4")
		(26 "In12.Cu" signal "GND5")
		(28 "In13.Cu" signal "IN5")
		(30 "In14.Cu" signal "GND6")
		(32 "In15.Cu" signal "IN6")
		(34 "In16.Cu" signal "GND7")
		(2 "B.Cu" signal "BOTTOM")
		(9 "F.Adhes" user "F.Adhesive")
		(11 "B.Adhes" user "B.Adhesive")
		(13 "F.Paste" user "Package Geometry/Pastemask Top")
		(15 "B.Paste" user "Package Geometry/Pastemask Bottom")
		(5 "F.SilkS" user "Ref Des/Silkscreen Top")
		(7 "B.SilkS" user "Ref Des/Silkscreen Bottom")
		(1 "F.Mask" user "Board Geometry/Soldermask Top")
		(3 "B.Mask" user "Board Geometry/Soldermask Bottom")
		(17 "Dwgs.User" user "User.Drawings")
		(19 "Cmts.User" user "User.Comments")
		(21 "Eco1.User" user "User.Eco1")
		(23 "Eco2.User" user "User.Eco2")
		(25 "Edge.Cuts" user "Board Geometry/Outline")
		(27 "Margin" user)
		(31 "F.CrtYd" user "Package Geometry/Place Bound Top")
		(29 "B.CrtYd" user "Package Geometry/Place Bound Bottom")
		(35 "F.Fab" user "Ref Des/Assembly Top")
		(33 "B.Fab" user "Ref Des/Assembly Bottom")
	)
	(footprint ""
		(layer "F.Cu")
		(at 131.367276 -196.391784 -90)
		(property "Reference" "U441"
			(at -1.053338 2.649474 0)
			(unlocked yes)
			(layer "F.SilkS")
			(effects
				(font
					(size 0.7874 0.5842)
					(thickness 0.1524)
				)
			)
		)
		(property "Value" ""
			(at 0 0 270)
			(layer "F.Fab")
			(effects
				(font
					(size 1.27 1.27)
				)
			)
		)
		(duplicate_pad_numbers_are_jumpers no)
		(fp_line
			(start -1.7272 1.1176)
			(end -1.7272 -1.1176)
			(stroke
				(width 0.1524)
				(type default)
			)
			(layer "F.SilkS")
		)
		(fp_line
			(start 1.7272 1.1176)
			(end -1.7272 1.1176)
			(stroke
				(width 0.1524)
				(type default)
			)
			(layer "F.SilkS")
		)
		(fp_line
			(start 0 -0.7366)
			(end -0.254 -1.1176)
			(stroke
				(width 0.1524)
				(type default)
			)
			(layer "F.SilkS")
		)
		(fp_line
			(start -0.254 -1.1176)
			(end -1.7272 -1.1176)
			(stroke
				(width 0.1524)
				(type default)
			)
			(layer "F.SilkS")
		)
		(fp_line
			(start 0.254 -1.1176)
			(end 0 -0.7366)
			(stroke
				(width 0.1524)
				(type default)
			)
			(layer "F.SilkS")
		)
		(fp_line
			(start 1.7272 -1.1176)
			(end 1.7272 1.1176)
			(stroke
				(width 0.1524)
				(type default)
			)
			(layer "F.SilkS")
		)
		(fp_line
			(start 1.7272 -1.1176)
			(end 0.254 -1.1176)
			(stroke
				(width 0.1524)
				(type default)
			)
			(layer "F.SilkS")
		)
		(fp_poly
			(pts
				(xy -1.9558 -0.649986) (xy -2.7178 -0.268986) (xy -2.7178 -1.030986)
			)
			(stroke
				(width 0)
				(type default)
			)
			(fill yes)
			(layer "F.SilkS")
		)
		(fp_line
			(start -1.5748 1.1176)
			(end 1.5748 1.1176)
			(stroke
				(width 0.1)
				(type default)
			)
			(layer "F.Fab")
		)
		(fp_line
			(start 1.5748 1.1176)
			(end 1.5748 -1.1176)
			(stroke
				(width 0.1)
				(type default)
			)
			(layer "F.Fab")
		)
		(fp_line
			(start -1.5748 -1.1176)
			(end -1.5748 1.1176)
			(stroke
				(width 0.1)
				(type default)
			)
			(layer "F.Fab")
		)
		(fp_line
			(start 1.5748 -1.1176)
			(end -1.5748 -1.1176)
			(stroke
				(width 0.1)
				(type default)
			)
			(layer "F.Fab")
		)
		(fp_poly
			(pts
				(xy -1.9558 -0.649986) (xy -2.7178 -0.268986) (xy -2.7178 -1.030986)
			)
			(stroke
				(width 0)
				(type default)
			)
			(fill yes)
			(layer "F.Fab")
		)
		(pad "1" smd rect
			(at -0.999998 -0.649986 180)
			(size 0.3556 1.1176)
			(layers "F.Cu" "F.Mask" "F.Paste")
			(net "NIC6_CLK_EN_R_N")
		)
		(pad "2" smd rect
			(at -0.999998 0 180)
			(size 0.3556 1.1176)
			(layers "F.Cu" "F.Mask" "F.Paste")
			(net "GND")
		)
		(pad "3" smd rect
			(at -0.999998 0.649986 180)
			(size 0.3556 1.1176)
			(layers "F.Cu" "F.Mask" "F.Paste")
			(net "NIC7_CLK_EN_R_N")
		)
		(pad "4" smd rect
			(at 0.999998 0.649986 180)
			(size 0.3556 1.1176)
			(layers "F.Cu" "F.Mask" "F.Paste")
			(net "NIC7_CLK_EN_BUF_N")
		)
		(pad "5" smd rect
			(at 0.999998 0 180)
			(size 0.3556 1.1176)
			(layers "F.Cu" "F.Mask" "F.Paste")
			(net "P3V3_AUX")
		)
		(pad "6" smd rect
			(at 0.999998 -0.649986 180)
			(size 0.3556 1.1176)
			(layers "F.Cu" "F.Mask" "F.Paste")
			(net "NIC6_CLK_EN_BUF_N")
		)
	)
	(footprint ""
		(layer "F.Cu")
		(at 78.134464 -87.599012)
		(property "Reference" "U15"
			(at -1.8034 -1.819148 0)
			(unlocked yes)
			(layer "F.SilkS")
			(effects
				(font
					(size 0.7874 0.5842)
					(thickness 0.1524)
				)
				(justify left)
			)
		)
		(property "Value" ""
			(at 0 0 0)
			(layer "F.Fab")
			(effects
				(font
					(size 1.27 1.27)
				)
			)
		)
		(duplicate_pad_numbers_are_jumpers no)
		(fp_line
			(start -1.684274 -1.074928)
			(end -0.381 -1.074928)
			(stroke
				(width 0.1524)
				(type default)
			)
			(layer "F.SilkS")
		)
		(fp_line
			(start -1.684274 1.074928)
			(end -1.684274 -1.074928)
			(stroke
				(width 0.1524)
				(type default)
			)
			(layer "F.SilkS")
		)
		(fp_line
			(start -0.381 -1.074928)
			(end 0 -0.625094)
			(stroke
				(width 0.1524)
				(type default)
			)
			(layer "F.SilkS")
		)
		(fp_line
			(start 0 -0.625094)
			(end 0.381 -1.074928)
			(stroke
				(width 0.1524)
				(type default)
			)
			(layer "F.SilkS")
		)
		(fp_line
			(start 0.381 -1.074928)
			(end 1.684274 -1.074928)
			(stroke
				(width 0.1524)
				(type default)
			)
			(layer "F.SilkS")
		)
		(fp_line
			(start 1.684274 -1.074928)
			(end 1.684274 1.074928)
			(stroke
				(width 0.1524)
				(type default)
			)
			(layer "F.SilkS")
		)
		(fp_line
			(start 1.684274 1.074928)
			(end -1.684274 1.074928)
			(stroke
				(width 0.1524)
				(type default)
			)
			(layer "F.SilkS")
		)
		(fp_poly
			(pts
				(xy -2.637282 -0.903986) (xy -2.637282 -0.395986) (xy -1.875282 -0.649986)
			)
			(stroke
				(width 0)
				(type default)
			)
			(fill yes)
			(layer "F.SilkS")
		)
		(fp_line
			(start -0.700024 -1.074928)
			(end -0.700024 1.074928)
			(stroke
				(width 0.1)
				(type default)
			)
			(layer "F.Fab")
		)
		(fp_line
			(start -0.700024 1.074928)
			(end 0.700024 1.074928)
			(stroke
				(width 0.1)
				(type default)
			)
			(layer "F.Fab")
		)
		(fp_line
			(start 0.700024 -1.074928)
			(end -0.700024 -1.074928)
			(stroke
				(width 0.1)
				(type default)
			)
			(layer "F.Fab")
		)
		(fp_line
			(start 0.700024 1.074928)
			(end 0.700024 -1.074928)
			(stroke
				(width 0.1)
				(type default)
			)
			(layer "F.Fab")
		)
		(fp_poly
			(pts
				(xy -2.637282 -0.903986) (xy -2.637282 -0.395986) (xy -1.875282 -0.649986)
			)
			(stroke
				(width 0)
				(type default)
			)
			(fill yes)
			(layer "F.Fab")
		)
		(pad "1" smd rect
			(at -1.100074 -0.649986 270)
			(size 0.4064 0.9144)
			(layers "F.Cu" "F.Mask" "F.Paste")
			(net "Net_8455")
		)
		(pad "2" smd rect
			(at -1.100074 0 270)
			(size 0.4064 0.9144)
			(layers "F.Cu" "F.Mask" "F.Paste")
			(net "RST_HP_NIC1_N")
		)
		(pad "3" smd rect
			(at -1.100074 0.649986 270)
			(size 0.4064 0.9144)
			(layers "F.Cu" "F.Mask" "F.Paste")
			(net "GND")
		)
		(pad "4" smd rect
			(at 1.100074 0.649986 270)
			(size 0.4064 0.9144)
			(layers "F.Cu" "F.Mask" "F.Paste")
			(net "RST_HP_NIC1_BUF_N")
		)
		(pad "5" smd rect
			(at 1.100074 -0.649986 270)
			(size 0.4064 0.9144)
			(layers "F.Cu" "F.Mask" "F.Paste")
			(net "P3V3_AUX")
		)
	)
	(footprint ""
		(layer "F.Cu")
		(at 117.940328 -32.848042 90)
		(property "Reference" "PC925"
			(at 0 0 90)
			(layer "F.SilkS")
			(hide yes)
			(effects
				(font
					(size 1.27 1.27)
				)
			)
		)
		(property "Value" ""
			(at 0 0 90)
			(layer "F.Fab")
			(effects
				(font
					(size 1.27 1.27)
				)
			)
		)
		(duplicate_pad_numbers_are_jumpers no)
		(fp_line
			(start 0.7874 -0.4064)
			(end 0.7874 0.4064)
			(stroke
				(width 0.1524)
				(type default)
			)
			(layer "F.SilkS")
		)
		(fp_line
			(start -0.7874 -0.4064)
			(end 0.7874 -0.4064)
			(stroke
				(width 0.1524)
				(type default)
			)
			(layer "F.SilkS")
		)
		(fp_line
			(start 0.7874 0.4064)
			(end -0.7874 0.4064)
			(stroke
				(width 0.1524)
				(type default)
			)
			(layer "F.SilkS")
		)
		(fp_line
			(start -0.7874 0.4064)
			(end -0.7874 -0.4064)
			(stroke
				(width 0.1524)
				(type default)
			)
			(layer "F.SilkS")
		)
		(fp_line
			(start -0.12065 -0.305054)
			(end -0.12065 -0.2794)
			(stroke
				(width 0.1)
				(type default)
			)
			(layer "F.Fab")
		)
		(fp_line
			(start -0.67945 -0.305054)
			(end -0.12065 -0.305054)
			(stroke
				(width 0.1)
				(type default)
			)
			(layer "F.Fab")
		)
		(fp_line
			(start 0.67945 -0.3048)
			(end 0.67945 0.3048)
			(stroke
				(width 0.1)
				(type default)
			)
			(layer "F.Fab")
		)
		(fp_line
			(start 0.12065 -0.3048)
			(end 0.67945 -0.3048)
			(stroke
				(width 0.1)
				(type default)
			)
			(layer "F.Fab")
		)
		(fp_line
			(start 0.12065 -0.2794)
			(end 0.12065 -0.3048)
			(stroke
				(width 0.1)
				(type default)
			)
			(layer "F.Fab")
		)
		(fp_line
			(start -0.12065 -0.2794)
			(end 0.12065 -0.2794)
			(stroke
				(width 0.1)
				(type default)
			)
			(layer "F.Fab")
		)
		(fp_line
			(start 0.120396 0.2794)
			(end -0.12065 0.2794)
			(stroke
				(width 0.1)
				(type default)
			)
			(layer "F.Fab")
		)
		(fp_line
			(start -0.12065 0.2794)
			(end -0.12065 0.3048)
			(stroke
				(width 0.1)
				(type default)
			)
			(layer "F.Fab")
		)
		(fp_line
			(start 0.67945 0.3048)
			(end 0.120396 0.3048)
			(stroke
				(width 0.1)
				(type default)
			)
			(layer "F.Fab")
		)
		(fp_line
			(start 0.120396 0.3048)
			(end 0.120396 0.2794)
			(stroke
				(width 0.1)
				(type default)
			)
			(layer "F.Fab")
		)
		(fp_line
			(start -0.12065 0.3048)
			(end -0.67945 0.3048)
			(stroke
				(width 0.1)
				(type default)
			)
			(layer "F.Fab")
		)
		(fp_line
			(start -0.67945 0.3048)
			(end -0.67945 -0.305054)
			(stroke
				(width 0.1)
				(type default)
			)
			(layer "F.Fab")
		)
		(pad "1" smd circle
			(at -0.40005 0 90)
			(size 0 0)
			(layers "F.Cu" "F.Mask" "F.Paste")
			(net "P3V3_SSD4_CO_DV_DT")
		)
		(pad "2" smd circle
			(at 0.40005 0 90)
			(size 0 0)
			(layers "F.Cu" "F.Mask" "F.Paste")
			(net "GND")
		)
	)
	(footprint ""
		(layer "F.Cu")
		(at 336.467704 -55.083456)
		(property "Reference" "PC432"
			(at 0 0 0)
			(layer "F.SilkS")
			(hide yes)
			(effects
				(font
					(size 1.27 1.27)
				)
			)
		)
		(property "Value" ""
			(at 0 0 0)
			(layer "F.Fab")
			(effects
				(font
					(size 1.27 1.27)
				)
			)
		)
		(duplicate_pad_numbers_are_jumpers no)
		(fp_line
			(start -0.7874 -0.4064)
			(end 0.7874 -0.4064)
			(stroke
				(width 0.1524)
				(type default)
			)
			(layer "F.SilkS")
		)
		(fp_line
			(start -0.7874 0.4064)
			(end -0.7874 -0.4064)
			(stroke
				(width 0.1524)
				(type default)
			)
			(layer "F.SilkS")
		)
		(fp_line
			(start 0.7874 -0.4064)
			(end 0.7874 0.4064)
			(stroke
				(width 0.1524)
				(type default)
			)
			(layer "F.SilkS")
		)
		(fp_line
			(start 0.7874 0.4064)
			(end -0.7874 0.4064)
			(stroke
				(width 0.1524)
				(type default)
			)
			(layer "F.SilkS")
		)
		(fp_line
			(start -0.67945 -0.305054)
			(end -0.12065 -0.305054)
			(stroke
				(width 0.1)
				(type default)
			)
			(layer "F.Fab")
		)
		(fp_line
			(start -0.67945 0.3048)
			(end -0.67945 -0.305054)
			(stroke
				(width 0.1)
				(type default)
			)
			(layer "F.Fab")
		)
		(fp_line
			(start -0.12065 -0.305054)
			(end -0.12065 -0.2794)
			(stroke
				(width 0.1)
				(type default)
			)
			(layer "F.Fab")
		)
		(fp_line
			(start -0.12065 -0.2794)
			(end 0.12065 -0.2794)
			(stroke
				(width 0.1)
				(type default)
			)
			(layer "F.Fab")
		)
		(fp_line
			(start -0.12065 0.2794)
			(end -0.12065 0.3048)
			(stroke
				(width 0.1)
				(type default)
			)
			(layer "F.Fab")
		)
		(fp_line
			(start -0.12065 0.3048)
			(end -0.67945 0.3048)
			(stroke
				(width 0.1)
				(type default)
			)
			(layer "F.Fab")
		)
		(fp_line
			(start 0.120396 0.2794)
			(end -0.12065 0.2794)
			(stroke
				(width 0.1)
				(type default)
			)
			(layer "F.Fab")
		)
		(fp_line
			(start 0.120396 0.3048)
			(end 0.120396 0.2794)
			(stroke
				(width 0.1)
				(type default)
			)
			(layer "F.Fab")
		)
		(fp_line
			(start 0.12065 -0.3048)
			(end 0.67945 -0.3048)
			(stroke
				(width 0.1)
				(type default)
			)
			(layer "F.Fab")
		)
		(fp_line
			(start 0.12065 -0.2794)
			(end 0.12065 -0.3048)
			(stroke
				(width 0.1)
				(type default)
			)
			(layer "F.Fab")
		)
		(fp_line
			(start 0.67945 -0.3048)
			(end 0.67945 0.3048)
			(stroke
				(width 0.1)
				(type default)
			)
			(layer "F.Fab")
		)
		(fp_line
			(start 0.67945 0.3048)
			(end 0.120396 0.3048)
			(stroke
				(width 0.1)
				(type default)
			)
			(layer "F.Fab")
		)
		(pad "1" smd circle
			(at -0.40005 0)
			(size 0 0)
			(layers "F.Cu" "F.Mask" "F.Paste")
			(net "P5V_AUX")
		)
		(pad "2" smd circle
			(at 0.40005 0)
			(size 0 0)
			(layers "F.Cu" "F.Mask" "F.Paste")
			(net "GND")
		)
	)
	(footprint ""
		(layer "F.Cu")
		(at 331.175614 -121.509028)
		(property "Reference" "PR246"
			(at 0 0 0)
			(layer "F.SilkS")
			(hide yes)
			(effects
				(font
					(size 1.27 1.27)
				)
			)
		)
		(property "Value" ""
			(at 0 0 0)
			(layer "F.Fab")
			(effects
				(font
					(size 1.27 1.27)
				)
			)
		)
		(duplicate_pad_numbers_are_jumpers no)
		(fp_line
			(start -0.7874 -0.4064)
			(end 0.7874 -0.4064)
			(stroke
				(width 0.1524)
				(type default)
			)
			(layer "F.SilkS")
		)
		(fp_line
			(start -0.7874 0.4064)
			(end -0.7874 -0.4064)
			(stroke
				(width 0.1524)
				(type default)
			)
			(layer "F.SilkS")
		)
		(fp_line
			(start 0.7874 -0.4064)
			(end 0.7874 0.4064)
			(stroke
				(width 0.1524)
				(type default)
			)
			(layer "F.SilkS")
		)
		(fp_line
			(start 0.7874 0.4064)
			(end -0.7874 0.4064)
			(stroke
				(width 0.1524)
				(type default)
			)
			(layer "F.SilkS")
		)
		(fp_line
			(start -0.67945 -0.305054)
			(end -0.12065 -0.305054)
			(stroke
				(width 0.1)
				(type default)
			)
			(layer "F.Fab")
		)
		(fp_line
			(start -0.67945 0.3048)
			(end -0.67945 -0.305054)
			(stroke
				(width 0.1)
				(type default)
			)
			(layer "F.Fab")
		)
		(fp_line
			(start -0.12065 -0.305054)
			(end -0.12065 -0.2794)
			(stroke
				(width 0.1)
				(type default)
			)
			(layer "F.Fab")
		)
		(fp_line
			(start -0.12065 -0.2794)
			(end 0.12065 -0.2794)
			(stroke
				(width 0.1)
				(type default)
			)
			(layer "F.Fab")
		)
		(fp_line
			(start -0.12065 0.2794)
			(end -0.12065 0.3048)
			(stroke
				(width 0.1)
				(type default)
			)
			(layer "F.Fab")
		)
		(fp_line
			(start -0.12065 0.3048)
			(end -0.67945 0.3048)
			(stroke
				(width 0.1)
				(type default)
			)
			(layer "F.Fab")
		)
		(fp_line
			(start 0.120396 0.2794)
			(end -0.12065 0.2794)
			(stroke
				(width 0.1)
				(type default)
			)
			(layer "F.Fab")
		)
		(fp_line
			(start 0.120396 0.3048)
			(end 0.120396 0.2794)
			(stroke
				(width 0.1)
				(type default)
			)
			(layer "F.Fab")
		)
		(fp_line
			(start 0.12065 -0.3048)
			(end 0.67945 -0.3048)
			(stroke
				(width 0.1)
				(type default)
			)
			(layer "F.Fab")
		)
		(fp_line
			(start 0.12065 -0.2794)
			(end 0.12065 -0.3048)
			(stroke
				(width 0.1)
				(type default)
			)
			(layer "F.Fab")
		)
		(fp_line
			(start 0.67945 -0.3048)
			(end 0.67945 0.3048)
			(stroke
				(width 0.1)
				(type default)
			)
			(layer "F.Fab")
		)
		(fp_line
			(start 0.67945 0.3048)
			(end 0.120396 0.3048)
			(stroke
				(width 0.1)
				(type default)
			)
			(layer "F.Fab")
		)
		(pad "1" smd circle
			(at -0.40005 0)
			(size 0 0)
			(layers "F.Cu" "F.Mask" "F.Paste")
			(net "P3V3_NIC5_OCP")
		)
		(pad "2" smd circle
			(at 0.40005 0)
			(size 0 0)
			(layers "F.Cu" "F.Mask" "F.Paste")
			(net "GND")
		)
	)
	(footprint ""
		(layer "F.Cu")
		(at 250.922536 -44.341542 90)
		(property "Reference" "R602"
			(at 0 0 90)
			(layer "F.SilkS")
			(hide yes)
			(effects
				(font
					(size 1.27 1.27)
				)
			)
		)
		(property "Value" ""
			(at 0 0 90)
			(layer "F.Fab")
			(effects
				(font
					(size 1.27 1.27)
				)
			)
		)
		(duplicate_pad_numbers_are_jumpers no)
		(fp_line
			(start 0.7874 -0.4064)
			(end 0.7874 0.4064)
			(stroke
				(width 0.1524)
				(type default)
			)
			(layer "F.SilkS")
		)
		(fp_line
			(start -0.7874 -0.4064)
			(end 0.7874 -0.4064)
			(stroke
				(width 0.1524)
				(type default)
			)
			(layer "F.SilkS")
		)
		(fp_line
			(start 0.7874 0.4064)
			(end -0.7874 0.4064)
			(stroke
				(width 0.1524)
				(type default)
			)
			(layer "F.SilkS")
		)
		(fp_line
			(start -0.7874 0.4064)
			(end -0.7874 -0.4064)
			(stroke
				(width 0.1524)
				(type default)
			)
			(layer "F.SilkS")
		)
		(fp_line
			(start -0.12065 -0.305054)
			(end -0.12065 -0.2794)
			(stroke
				(width 0.1)
				(type default)
			)
			(layer "F.Fab")
		)
		(fp_line
			(start -0.67945 -0.305054)
			(end -0.12065 -0.305054)
			(stroke
				(width 0.1)
				(type default)
			)
			(layer "F.Fab")
		)
		(fp_line
			(start 0.67945 -0.3048)
			(end 0.67945 0.3048)
			(stroke
				(width 0.1)
				(type default)
			)
			(layer "F.Fab")
		)
		(fp_line
			(start 0.12065 -0.3048)
			(end 0.67945 -0.3048)
			(stroke
				(width 0.1)
				(type default)
			)
			(layer "F.Fab")
		)
		(fp_line
			(start 0.12065 -0.2794)
			(end 0.12065 -0.3048)
			(stroke
				(width 0.1)
				(type default)
			)
			(layer "F.Fab")
		)
		(fp_line
			(start -0.12065 -0.2794)
			(end 0.12065 -0.2794)
			(stroke
				(width 0.1)
				(type default)
			)
			(layer "F.Fab")
		)
		(fp_line
			(start 0.120396 0.2794)
			(end -0.12065 0.2794)
			(stroke
				(width 0.1)
				(type default)
			)
			(layer "F.Fab")
		)
		(fp_line
			(start -0.12065 0.2794)
			(end -0.12065 0.3048)
			(stroke
				(width 0.1)
				(type default)
			)
			(layer "F.Fab")
		)
		(fp_line
			(start 0.67945 0.3048)
			(end 0.120396 0.3048)
			(stroke
				(width 0.1)
				(type default)
			)
			(layer "F.Fab")
		)
		(fp_line
			(start 0.120396 0.3048)
			(end 0.120396 0.2794)
			(stroke
				(width 0.1)
				(type default)
			)
			(layer "F.Fab")
		)
		(fp_line
			(start -0.12065 0.3048)
			(end -0.67945 0.3048)
			(stroke
				(width 0.1)
				(type default)
			)
			(layer "F.Fab")
		)
		(fp_line
			(start -0.67945 0.3048)
			(end -0.67945 -0.305054)
			(stroke
				(width 0.1)
				(type default)
			)
			(layer "F.Fab")
		)
		(pad "1" smd circle
			(at -0.40005 0 90)
			(size 0 0)
			(layers "F.Cu" "F.Mask" "F.Paste")
			(net "P12V_SSD8")
		)
		(pad "2" smd circle
			(at 0.40005 0 90)
			(size 0 0)
			(layers "F.Cu" "F.Mask" "F.Paste")
			(net "P12V_SSD8_VIN_N")
		)
	)
)
